(kicad_pcb
	(version 20260206)
	(generator "pcbnew")
	(generator_version "10.0")
	(general
		(thickness 1.6)
		(legacy_teardrops no)
	)
	(paper "A4")
	(title_block
		(title "Bryce Canyon_IOM_IOC_16318-2_OCP.brd")
		(comment 1 "Bryce Canyon / footprints 1340-1346 of 1605")
	)
	(layers
		(0 "F.Cu" signal "TOP")
		(4 "In1.Cu" signal "L2GND")
		(6 "In2.Cu" signal "L3")
		(8 "In3.Cu" signal "L4VCC")
		(10 "In4.Cu" signal "L5VCC")
		(12 "In5.Cu" signal "L6")
		(14 "In6.Cu" signal "L7GND")
		(2 "B.Cu" signal "BOTTOM")
		(9 "F.Adhes" user "F.Adhesive")
		(11 "B.Adhes" user "B.Adhesive")
		(13 "F.Paste" user "Package Geometry/Pastemask Top")
		(15 "B.Paste" user "Package Geometry/Pastemask Bottom")
		(5 "F.SilkS" user "Ref Des/Silkscreen Top")
		(7 "B.SilkS" user "Ref Des/Silkscreen Bottom")
		(1 "F.Mask" user "Board Geometry/Soldermask Top")
		(3 "B.Mask" user "Board Geometry/Soldermask Bottom")
		(17 "Dwgs.User" user "User.Drawings")
		(19 "Cmts.User" user "User.Comments")
		(21 "Eco1.User" user "User.Eco1")
		(23 "Eco2.User" user "User.Eco2")
		(25 "Edge.Cuts" user "Board Geometry/Outline")
		(27 "Margin" user)
		(31 "F.CrtYd" user "Package Geometry/Place Bound Top")
		(29 "B.CrtYd" user "Package Geometry/Place Bound Bottom")
		(35 "F.Fab" user "Ref Des/Assembly Top")
		(33 "B.Fab" user "Ref Des/Assembly Bottom")
	)
	(footprint ""
		(layer "B.Cu")
		(at 61.9506 -137.9474 -90)
		(property "Reference" "R785"
			(at 0 0 90)
			(layer "B.SilkS")
			(hide yes)
			(effects
				(font
					(size 1.27 1.27)
				)
				(justify mirror)
			)
		)
		(property "Value" "10KR2F-2-GP"
			(at -0.064008 -3.993896 270)
			(unlocked yes)
			(layer "B.Fab")
			(hide yes)
			(effects
				(font
					(size 1.016 1.016)
					(thickness 0.1524)
				)
				(justify mirror)
			)
		)
		(property "Device Type" "R402H16"
			(at -0.064008 -5.517896 270)
			(unlocked yes)
			(layer "B.Fab")
			(hide yes)
			(effects
				(font
					(size 1.016 1.016)
					(thickness 0.1524)
				)
				(justify mirror)
			)
		)
		(duplicate_pad_numbers_are_jumpers no)
		(fp_line
			(start -0.508 -0.9398)
			(end 0.508 -0.9398)
			(stroke
				(width 0.1524)
				(type default)
			)
			(layer "B.SilkS")
		)
		(fp_line
			(start 0.508 -0.9398)
			(end 0.508 0.9398)
			(stroke
				(width 0.1524)
				(type default)
			)
			(layer "B.SilkS")
		)
		(fp_rect
			(start 0.508 0.9398)
			(end -0.508 -0.9398)
			(stroke
				(width 0)
				(type default)
			)
			(fill no)
			(layer "B.CrtYd")
		)
		(fp_rect
			(start 0.508 0.9398)
			(end -0.508 -0.9398)
			(stroke
				(width 0)
				(type default)
			)
			(fill no)
			(layer "B.Fab")
		)
		(pad "1" smd custom
			(at 0 -0.4445 90)
			(size 0.1397 0.1397)
			(layers "B.Cu" "B.Mask" "B.Paste")
			(net "P3V3_STBY")
			(options
				(clearance outline)
				(anchor circle)
			)
			(primitives
				(gr_poly
					(pts
						(arc
							(start -0.1778 0.2794)
							(mid -0.249642 0.249642)
							(end -0.2794 0.1778)
						)
						(arc
							(start -0.2794 -0.1778)
							(mid -0.249642 -0.249642)
							(end -0.1778 -0.2794)
						)
						(arc
							(start 0.1778 -0.2794)
							(mid 0.249642 -0.249642)
							(end 0.2794 -0.1778)
						)
						(arc
							(start 0.2794 0.1778)
							(mid 0.249642 0.249642)
							(end 0.1778 0.2794)
						)
					)
					(width 0)
					(fill yes)
				)
			)
		)
		(pad "2" smd custom
			(at 0 0.4445 90)
			(size 0.1397 0.1397)
			(layers "B.Cu" "B.Mask" "B.Paste")
			(net "TP_BMC_GPIOA0")
			(options
				(clearance outline)
				(anchor circle)
			)
			(primitives
				(gr_poly
					(pts
						(arc
							(start -0.1778 0.2794)
							(mid -0.249642 0.249642)
							(end -0.2794 0.1778)
						)
						(arc
							(start -0.2794 -0.1778)
							(mid -0.249642 -0.249642)
							(end -0.1778 -0.2794)
						)
						(arc
							(start 0.1778 -0.2794)
							(mid 0.249642 -0.249642)
							(end 0.2794 -0.1778)
						)
						(arc
							(start 0.2794 0.1778)
							(mid 0.249642 0.249642)
							(end 0.1778 0.2794)
						)
					)
					(width 0)
					(fill yes)
				)
			)
		)
	)
	(footprint ""
		(layer "B.Cu")
		(at 54.6354 -135.7122 180)
		(property "Reference" "R353"
			(at 0 0 0)
			(layer "B.SilkS")
			(hide yes)
			(effects
				(font
					(size 1.27 1.27)
				)
				(justify mirror)
			)
		)
		(property "Value" "4K7R2F-GP"
			(at -0.064008 -3.993896 180)
			(unlocked yes)
			(layer "B.Fab")
			(hide yes)
			(effects
				(font
					(size 1.016 1.016)
					(thickness 0.1524)
				)
				(justify mirror)
			)
		)
		(property "Device Type" "R402H16"
			(at -0.064008 -5.517896 180)
			(unlocked yes)
			(layer "B.Fab")
			(hide yes)
			(effects
				(font
					(size 1.016 1.016)
					(thickness 0.1524)
				)
				(justify mirror)
			)
		)
		(duplicate_pad_numbers_are_jumpers no)
		(fp_line
			(start 0.508 -0.9398)
			(end 0.508 0.9398)
			(stroke
				(width 0.1524)
				(type default)
			)
			(layer "B.SilkS")
		)
		(fp_line
			(start -0.508 -0.9398)
			(end 0.508 -0.9398)
			(stroke
				(width 0.1524)
				(type default)
			)
			(layer "B.SilkS")
		)
		(fp_rect
			(start 0.508 0.9398)
			(end -0.508 -0.9398)
			(stroke
				(width 0)
				(type default)
			)
			(fill no)
			(layer "B.CrtYd")
		)
		(fp_rect
			(start 0.508 0.9398)
			(end -0.508 -0.9398)
			(stroke
				(width 0)
				(type default)
			)
			(fill no)
			(layer "B.Fab")
		)
		(pad "1" smd custom
			(at 0 -0.4445)
			(size 0.1397 0.1397)
			(layers "B.Cu" "B.Mask" "B.Paste")
			(net "P3V3_STBY")
			(options
				(clearance outline)
				(anchor circle)
			)
			(primitives
				(gr_poly
					(pts
						(arc
							(start -0.1778 0.2794)
							(mid -0.249642 0.249642)
							(end -0.2794 0.1778)
						)
						(arc
							(start -0.2794 -0.1778)
							(mid -0.249642 -0.249642)
							(end -0.1778 -0.2794)
						)
						(arc
							(start 0.1778 -0.2794)
							(mid 0.249642 -0.249642)
							(end 0.2794 -0.1778)
						)
						(arc
							(start 0.2794 0.1778)
							(mid 0.249642 0.249642)
							(end 0.1778 0.2794)
						)
					)
					(width 0)
					(fill yes)
				)
			)
		)
		(pad "2" smd custom
			(at 0 0.4445)
			(size 0.1397 0.1397)
			(layers "B.Cu" "B.Mask" "B.Paste")
			(net "SLOTID_1")
			(options
				(clearance outline)
				(anchor circle)
			)
			(primitives
				(gr_poly
					(pts
						(arc
							(start -0.1778 0.2794)
							(mid -0.249642 0.249642)
							(end -0.2794 0.1778)
						)
						(arc
							(start -0.2794 -0.1778)
							(mid -0.249642 -0.249642)
							(end -0.1778 -0.2794)
						)
						(arc
							(start 0.1778 -0.2794)
							(mid 0.249642 -0.249642)
							(end 0.2794 -0.1778)
						)
						(arc
							(start 0.2794 0.1778)
							(mid 0.249642 0.249642)
							(end 0.1778 0.2794)
						)
					)
					(width 0)
					(fill yes)
				)
			)
		)
	)
	(footprint ""
		(layer "B.Cu")
		(at 24.666702 -143.811244 180)
		(property "Reference" "C69"
			(at 0 0 0)
			(layer "B.SilkS")
			(hide yes)
			(effects
				(font
					(size 1.27 1.27)
				)
				(justify mirror)
			)
		)
		(property "Value" "SCD1U16V2KX-3GP"
			(at -1.1811 -2.7051 180)
			(unlocked yes)
			(layer "B.Fab")
			(hide yes)
			(effects
				(font
					(size 1.016 1.016)
					(thickness 0.1524)
				)
				(justify mirror)
			)
		)
		(property "Device Type" "C402H22"
			(at -1.1811 -4.2291 180)
			(unlocked yes)
			(layer "B.Fab")
			(hide yes)
			(effects
				(font
					(size 1.016 1.016)
					(thickness 0.1524)
				)
				(justify mirror)
			)
		)
		(duplicate_pad_numbers_are_jumpers no)
		(fp_rect
			(start 0.4318 0.9525)
			(end -0.4318 -0.9525)
			(stroke
				(width 0)
				(type default)
			)
			(fill no)
			(layer "B.CrtYd")
		)
		(fp_rect
			(start 0.4318 0.9525)
			(end -0.4318 -0.9525)
			(stroke
				(width 0)
				(type default)
			)
			(fill no)
			(layer "B.Fab")
		)
		(pad "1" smd custom
			(at 0 -0.4445)
			(size 0.1524 0.1524)
			(layers "B.Cu" "B.Mask" "B.Paste")
			(net "GND")
			(options
				(clearance outline)
				(anchor circle)
			)
			(primitives
				(gr_poly
					(pts
						(arc
							(start 0.3048 0.2032)
							(mid 0.275042 0.275042)
							(end 0.2032 0.3048)
						)
						(arc
							(start -0.2032 0.3048)
							(mid -0.275042 0.275042)
							(end -0.3048 0.2032)
						)
						(arc
							(start -0.3048 -0.2032)
							(mid -0.275042 -0.275042)
							(end -0.2032 -0.3048)
						)
						(arc
							(start 0.2032 -0.3048)
							(mid 0.275042 -0.275042)
							(end 0.3048 -0.2032)
						)
					)
					(width 0)
					(fill yes)
				)
			)
		)
		(pad "2" smd custom
			(at 0 0.4445)
			(size 0.1524 0.1524)
			(layers "B.Cu" "B.Mask" "B.Paste")
			(net "P1V2_STBY")
			(options
				(clearance outline)
				(anchor circle)
			)
			(primitives
				(gr_poly
					(pts
						(arc
							(start 0.3048 0.2032)
							(mid 0.275042 0.275042)
							(end 0.2032 0.3048)
						)
						(arc
							(start -0.2032 0.3048)
							(mid -0.275042 0.275042)
							(end -0.3048 0.2032)
						)
						(arc
							(start -0.3048 -0.2032)
							(mid -0.275042 -0.275042)
							(end -0.2032 -0.3048)
						)
						(arc
							(start 0.2032 -0.3048)
							(mid 0.275042 -0.275042)
							(end 0.3048 -0.2032)
						)
					)
					(width 0)
					(fill yes)
				)
			)
		)
	)
	(footprint ""
		(layer "B.Cu")
		(at 62.52083 -142.142972)
		(property "Reference" "R195"
			(at 0 0 0)
			(layer "B.SilkS")
			(hide yes)
			(effects
				(font
					(size 1.27 1.27)
				)
				(justify mirror)
			)
		)
		(property "Value" "2K2R2F-GP"
			(at -0.064008 -3.993896 0)
			(unlocked yes)
			(layer "B.Fab")
			(hide yes)
			(effects
				(font
					(size 1.016 1.016)
					(thickness 0.1524)
				)
				(justify mirror)
			)
		)
		(property "Device Type" "R402H16"
			(at -0.064008 -5.517896 0)
			(unlocked yes)
			(layer "B.Fab")
			(hide yes)
			(effects
				(font
					(size 1.016 1.016)
					(thickness 0.1524)
				)
				(justify mirror)
			)
		)
		(duplicate_pad_numbers_are_jumpers no)
		(fp_line
			(start -0.508 -0.9398)
			(end 0.508 -0.9398)
			(stroke
				(width 0.1524)
				(type default)
			)
			(layer "B.SilkS")
		)
		(fp_line
			(start 0.508 -0.9398)
			(end 0.508 0.9398)
			(stroke
				(width 0.1524)
				(type default)
			)
			(layer "B.SilkS")
		)
		(fp_rect
			(start 0.508 0.9398)
			(end -0.508 -0.9398)
			(stroke
				(width 0)
				(type default)
			)
			(fill no)
			(layer "B.CrtYd")
		)
		(fp_rect
			(start 0.508 0.9398)
			(end -0.508 -0.9398)
			(stroke
				(width 0)
				(type default)
			)
			(fill no)
			(layer "B.Fab")
		)
		(pad "1" smd custom
			(at 0 -0.4445 180)
			(size 0.1397 0.1397)
			(layers "B.Cu" "B.Mask" "B.Paste")
			(net "I2C_EXP_LOC_SCL_OUT")
			(options
				(clearance outline)
				(anchor circle)
			)
			(primitives
				(gr_poly
					(pts
						(arc
							(start -0.1778 0.2794)
							(mid -0.249642 0.249642)
							(end -0.2794 0.1778)
						)
						(arc
							(start -0.2794 -0.1778)
							(mid -0.249642 -0.249642)
							(end -0.1778 -0.2794)
						)
						(arc
							(start 0.1778 -0.2794)
							(mid 0.249642 -0.249642)
							(end 0.2794 -0.1778)
						)
						(arc
							(start 0.2794 0.1778)
							(mid 0.249642 0.249642)
							(end 0.1778 0.2794)
						)
					)
					(width 0)
					(fill yes)
				)
			)
		)
		(pad "2" smd custom
			(at 0 0.4445 180)
			(size 0.1397 0.1397)
			(layers "B.Cu" "B.Mask" "B.Paste")
			(net "P3V3_STBY")
			(options
				(clearance outline)
				(anchor circle)
			)
			(primitives
				(gr_poly
					(pts
						(arc
							(start -0.1778 0.2794)
							(mid -0.249642 0.249642)
							(end -0.2794 0.1778)
						)
						(arc
							(start -0.2794 -0.1778)
							(mid -0.249642 -0.249642)
							(end -0.1778 -0.2794)
						)
						(arc
							(start 0.1778 -0.2794)
							(mid 0.249642 -0.249642)
							(end 0.2794 -0.1778)
						)
						(arc
							(start 0.2794 0.1778)
							(mid 0.249642 0.249642)
							(end 0.1778 0.2794)
						)
					)
					(width 0)
					(fill yes)
				)
			)
		)
	)
	(footprint ""
		(layer "B.Cu")
		(at 187.989718 -81.153 180)
		(property "Reference" "C304"
			(at 0 0 0)
			(layer "B.SilkS")
			(hide yes)
			(effects
				(font
					(size 1.27 1.27)
				)
				(justify mirror)
			)
		)
		(property "Value" "SCD22U10V1KX-GP"
			(at 2.8321 -1.7399 180)
			(unlocked yes)
			(layer "B.Fab")
			(hide yes)
			(effects
				(font
					(size 1.016 1.016)
					(thickness 0.1524)
				)
				(justify mirror)
			)
		)
		(property "Device Type" "C0201H13"
			(at 2.8321 -3.2639 180)
			(unlocked yes)
			(layer "B.Fab")
			(hide yes)
			(effects
				(font
					(size 1.016 1.016)
					(thickness 0.1524)
				)
				(justify mirror)
			)
		)
		(duplicate_pad_numbers_are_jumpers no)
		(fp_rect
			(start 0.2794 0.6477)
			(end -0.2794 -0.6477)
			(stroke
				(width 0)
				(type default)
			)
			(fill no)
			(layer "B.CrtYd")
		)
		(fp_rect
			(start 0.2794 0.6477)
			(end -0.2794 -0.6477)
			(stroke
				(width 0)
				(type default)
			)
			(fill no)
			(layer "B.Fab")
		)
		(pad "1" smd custom
			(at 0 -0.2794)
			(size 0.0762 0.0762)
			(layers "B.Cu" "B.Mask" "B.Paste")
			(net "PCIE_IOM_TO_COMP_15_DN_C")
			(options
				(clearance outline)
				(anchor circle)
			)
			(primitives
				(gr_poly
					(pts
						(arc
							(start 0.1524 0.127)
							(mid 0.137521 0.162921)
							(end 0.1016 0.1778)
						)
						(arc
							(start -0.1016 0.1778)
							(mid -0.137521 0.162921)
							(end -0.1524 0.127)
						)
						(arc
							(start -0.1524 -0.127)
							(mid -0.137521 -0.162921)
							(end -0.1016 -0.1778)
						)
						(arc
							(start 0.1016 -0.1778)
							(mid 0.137521 -0.162921)
							(end 0.1524 -0.127)
						)
					)
					(width 0)
					(fill yes)
				)
			)
		)
		(pad "2" smd custom
			(at 0 0.2794)
			(size 0.0762 0.0762)
			(layers "B.Cu" "B.Mask" "B.Paste")
			(net "PCIE_IOM_TO_COMP_15_DN")
			(options
				(clearance outline)
				(anchor circle)
			)
			(primitives
				(gr_poly
					(pts
						(arc
							(start 0.1524 0.127)
							(mid 0.137521 0.162921)
							(end 0.1016 0.1778)
						)
						(arc
							(start -0.1016 0.1778)
							(mid -0.137521 0.162921)
							(end -0.1524 0.127)
						)
						(arc
							(start -0.1524 -0.127)
							(mid -0.137521 -0.162921)
							(end -0.1016 -0.1778)
						)
						(arc
							(start 0.1016 -0.1778)
							(mid 0.137521 -0.162921)
							(end 0.1524 -0.127)
						)
					)
					(width 0)
					(fill yes)
				)
			)
		)
	)
	(footprint ""
		(layer "B.Cu")
		(at 44.6024 -131.318 -90)
		(property "Reference" "R293"
			(at 0 0 90)
			(layer "B.SilkS")
			(hide yes)
			(effects
				(font
					(size 1.27 1.27)
				)
				(justify mirror)
			)
		)
		(property "Value" "0R2J-2-GP"
			(at -0.064008 -3.993896 270)
			(unlocked yes)
			(layer "B.Fab")
			(hide yes)
			(effects
				(font
					(size 1.016 1.016)
					(thickness 0.1524)
				)
				(justify mirror)
			)
		)
		(property "Device Type" "R402H16"
			(at -0.064008 -5.517896 270)
			(unlocked yes)
			(layer "B.Fab")
			(hide yes)
			(effects
				(font
					(size 1.016 1.016)
					(thickness 0.1524)
				)
				(justify mirror)
			)
		)
		(duplicate_pad_numbers_are_jumpers no)
		(fp_line
			(start -0.508 -0.9398)
			(end 0.508 -0.9398)
			(stroke
				(width 0.1524)
				(type default)
			)
			(layer "B.SilkS")
		)
		(fp_line
			(start 0.508 -0.9398)
			(end 0.508 0.9398)
			(stroke
				(width 0.1524)
				(type default)
			)
			(layer "B.SilkS")
		)
		(fp_rect
			(start 0.508 0.9398)
			(end -0.508 -0.9398)
			(stroke
				(width 0)
				(type default)
			)
			(fill no)
			(layer "B.CrtYd")
		)
		(fp_rect
			(start 0.508 0.9398)
			(end -0.508 -0.9398)
			(stroke
				(width 0)
				(type default)
			)
			(fill no)
			(layer "B.Fab")
		)
		(pad "1" smd custom
			(at 0 -0.4445 90)
			(size 0.1397 0.1397)
			(layers "B.Cu" "B.Mask" "B.Paste")
			(net "IOM_FULL_PWR_EN")
			(options
				(clearance outline)
				(anchor circle)
			)
			(primitives
				(gr_poly
					(pts
						(arc
							(start -0.1778 0.2794)
							(mid -0.249642 0.249642)
							(end -0.2794 0.1778)
						)
						(arc
							(start -0.2794 -0.1778)
							(mid -0.249642 -0.249642)
							(end -0.1778 -0.2794)
						)
						(arc
							(start 0.1778 -0.2794)
							(mid 0.249642 -0.249642)
							(end 0.2794 -0.1778)
						)
						(arc
							(start 0.2794 0.1778)
							(mid 0.249642 0.249642)
							(end 0.1778 0.2794)
						)
					)
					(width 0)
					(fill yes)
				)
			)
		)
		(pad "2" smd custom
			(at 0 0.4445 90)
			(size 0.1397 0.1397)
			(layers "B.Cu" "B.Mask" "B.Paste")
			(net "IOM_FULL_PWR_EN_R")
			(options
				(clearance outline)
				(anchor circle)
			)
			(primitives
				(gr_poly
					(pts
						(arc
							(start -0.1778 0.2794)
							(mid -0.249642 0.249642)
							(end -0.2794 0.1778)
						)
						(arc
							(start -0.2794 -0.1778)
							(mid -0.249642 -0.249642)
							(end -0.1778 -0.2794)
						)
						(arc
							(start 0.1778 -0.2794)
							(mid 0.249642 -0.249642)
							(end 0.2794 -0.1778)
						)
						(arc
							(start 0.2794 0.1778)
							(mid 0.249642 0.249642)
							(end 0.1778 0.2794)
						)
					)
					(width 0)
					(fill yes)
				)
			)
		)
	)
	(footprint ""
		(layer "B.Cu")
		(at 96.139 -146.431)
		(property "Reference" "C127"
			(at 0 0 0)
			(layer "B.SilkS")
			(hide yes)
			(effects
				(font
					(size 1.27 1.27)
				)
				(justify mirror)
			)
		)
		(property "Value" "SCD1U16V2KX-3GP"
			(at -1.1811 -2.7051 0)
			(unlocked yes)
			(layer "B.Fab")
			(hide yes)
			(effects
				(font
					(size 1.016 1.016)
					(thickness 0.1524)
				)
				(justify mirror)
			)
		)
		(property "Device Type" "C402H22"
			(at -1.1811 -4.2291 0)
			(unlocked yes)
			(layer "B.Fab")
			(hide yes)
			(effects
				(font
					(size 1.016 1.016)
					(thickness 0.1524)
				)
				(justify mirror)
			)
		)
		(duplicate_pad_numbers_are_jumpers no)
		(fp_rect
			(start 0.4318 0.9525)
			(end -0.4318 -0.9525)
			(stroke
				(width 0)
				(type default)
			)
			(fill no)
			(layer "B.CrtYd")
		)
		(fp_rect
			(start 0.4318 0.9525)
			(end -0.4318 -0.9525)
			(stroke
				(width 0)
				(type default)
			)
			(fill no)
			(layer "B.Fab")
		)
		(pad "1" smd custom
			(at 0 -0.4445 180)
			(size 0.1524 0.1524)
			(layers "B.Cu" "B.Mask" "B.Paste")
			(net "P3V3_STBY")
			(options
				(clearance outline)
				(anchor circle)
			)
			(primitives
				(gr_poly
					(pts
						(arc
							(start 0.3048 0.2032)
							(mid 0.275042 0.275042)
							(end 0.2032 0.3048)
						)
						(arc
							(start -0.2032 0.3048)
							(mid -0.275042 0.275042)
							(end -0.3048 0.2032)
						)
						(arc
							(start -0.3048 -0.2032)
							(mid -0.275042 -0.275042)
							(end -0.2032 -0.3048)
						)
						(arc
							(start 0.2032 -0.3048)
							(mid 0.275042 -0.275042)
							(end 0.3048 -0.2032)
						)
					)
					(width 0)
					(fill yes)
				)
			)
		)
		(pad "2" smd custom
			(at 0 0.4445 180)
			(size 0.1524 0.1524)
			(layers "B.Cu" "B.Mask" "B.Paste")
			(net "GND")
			(options
				(clearance outline)
				(anchor circle)
			)
			(primitives
				(gr_poly
					(pts
						(arc
							(start 0.3048 0.2032)
							(mid 0.275042 0.275042)
							(end 0.2032 0.3048)
						)
						(arc
							(start -0.2032 0.3048)
							(mid -0.275042 0.275042)
							(end -0.3048 0.2032)
						)
						(arc
							(start -0.3048 -0.2032)
							(mid -0.275042 -0.275042)
							(end -0.2032 -0.3048)
						)
						(arc
							(start 0.2032 -0.3048)
							(mid 0.275042 -0.275042)
							(end 0.3048 -0.2032)
						)
					)
					(width 0)
					(fill yes)
				)
			)
		)
	)
)
